FILE_TYPE=LIBRARY_PARTS;
primitive 'SCHOTTKY_DUAL_12A_3C';
  pin
    'A':
      PIN_NUMBER='(2)';
      INPUT_LOAD='(-0.01,0.01)';
    'B':
      PIN_NUMBER='(1)';
      INPUT_LOAD='(-0.01,0.01)';
    'C':
      PIN_NUMBER='(3)';
      BIDIRECTIONAL='TRUE';
      INPUT_LOAD='(-0.01,0.01)';
      OUTPUT_LOAD='(1.0,-1.0)';
  end_pin;
  body
    PART_NAME='SCHOTTKY_DUAL_12A_3C';
    BODY_NAME='SCHOTTKY_DUAL_12A_3C';
    PHYS_DES_PREFIX='U';
    CLASS='IC';
  end_body;
end_primitive;

END.
